(kicad_pcb
	(version 20260206)
	(generator "pcbnew")
	(generator_version "10.0")
	(general
		(thickness 1.6)
		(legacy_teardrops no)
	)
	(paper "A4")
	(title_block
		(title "Bryce Canyon_Front Panel_16369-1_OCP.brd")
		(comment 1 "Bryce Canyon / footprints 109-115 of 154")
	)
	(layers
		(0 "F.Cu" signal "TOP")
		(4 "In1.Cu" signal "L2GND")
		(6 "In2.Cu" signal "L3VCC")
		(2 "B.Cu" signal "BOTTOM")
		(9 "F.Adhes" user "F.Adhesive")
		(11 "B.Adhes" user "B.Adhesive")
		(13 "F.Paste" user "Package Geometry/Pastemask Top")
		(15 "B.Paste" user "Package Geometry/Pastemask Bottom")
		(5 "F.SilkS" user "Ref Des/Silkscreen Top")
		(7 "B.SilkS" user "Ref Des/Silkscreen Bottom")
		(1 "F.Mask" user "Board Geometry/Soldermask Top")
		(3 "B.Mask" user "Board Geometry/Soldermask Bottom")
		(17 "Dwgs.User" user "User.Drawings")
		(19 "Cmts.User" user "User.Comments")
		(21 "Eco1.User" user "User.Eco1")
		(23 "Eco2.User" user "User.Eco2")
		(25 "Edge.Cuts" user "Board Geometry/Outline")
		(27 "Margin" user)
		(31 "F.CrtYd" user "Package Geometry/Place Bound Top")
		(29 "B.CrtYd" user "Package Geometry/Place Bound Bottom")
		(35 "F.Fab" user "Ref Des/Assembly Top")
		(33 "B.Fab" user "Ref Des/Assembly Bottom")
	)
	(footprint ""
		(layer "F.Cu")
		(at 2.02819 -56.892698)
		(property "Reference" "D3"
			(at 0 0 0)
			(layer "F.SilkS")
			(hide yes)
			(effects
				(font
					(size 1.27 1.27)
				)
			)
		)
		(property "Value" "PESD5V0S1BL-1-GP"
			(at 1.8923 -1.5621 0)
			(unlocked yes)
			(layer "F.Fab")
			(hide yes)
			(effects
				(font
					(size 1.016 1.016)
					(thickness 0.1524)
				)
			)
		)
		(property "Device Type" "SOD882-10D6-1H20"
			(at 1.8923 -3.0861 0)
			(unlocked yes)
			(layer "F.Fab")
			(hide yes)
			(effects
				(font
					(size 1.016 1.016)
					(thickness 0.1524)
				)
			)
		)
		(duplicate_pad_numbers_are_jumpers no)
		(fp_line
			(start -0.3048 -0.9271)
			(end 0.3048 -0.9271)
			(stroke
				(width 0.254)
				(type default)
			)
			(layer "F.SilkS")
		)
		(fp_rect
			(start -0.2921 0.4953)
			(end 0.2921 -0.4953)
			(stroke
				(width 0)
				(type default)
			)
			(fill no)
			(layer "F.CrtYd")
		)
		(fp_poly
			(pts
				(xy -0.4318 0.8001) (xy -0.4318 -0.266192) (xy -0.2921 -0.266192) (xy -0.2921 0.4953) (xy 0.2921 0.4953)
				(xy 0.2921 -0.4953) (xy -0.2921 -0.4953) (xy -0.2921 -0.2667) (xy -0.4318 -0.2667) (xy -0.4318 -0.8001)
				(xy 0.4318 -0.8001) (xy 0.4318 0.8001)
			)
			(stroke
				(width 0)
				(type default)
			)
			(fill no)
			(layer "F.CrtYd")
		)
		(fp_rect
			(start -0.4318 0.8001)
			(end 0.4318 -0.8001)
			(stroke
				(width 0)
				(type default)
			)
			(fill no)
			(layer "F.Fab")
		)
		(pad "1" smd custom
			(at 0 -0.4445)
			(size 0.1143 0.1143)
			(layers "F.Cu" "F.Mask" "F.Paste")
			(net "P5V_VBUS_A")
			(options
				(clearance outline)
				(anchor circle)
			)
			(primitives
				(gr_poly
					(pts
						(arc
							(start -0.2032 0.2286)
							(mid -0.275042 0.198842)
							(end -0.3048 0.127)
						)
						(arc
							(start -0.3048 -0.127)
							(mid -0.275042 -0.198842)
							(end -0.2032 -0.2286)
						)
						(arc
							(start 0.2032 -0.2286)
							(mid 0.275042 -0.198842)
							(end 0.3048 -0.127)
						)
						(arc
							(start 0.3048 0.127)
							(mid 0.275042 0.198842)
							(end 0.2032 0.2286)
						)
					)
					(width 0)
					(fill yes)
				)
			)
		)
		(pad "2" smd custom
			(at 0 0.4445)
			(size 0.1143 0.1143)
			(layers "F.Cu" "F.Mask" "F.Paste")
			(net "GND")
			(options
				(clearance outline)
				(anchor circle)
			)
			(primitives
				(gr_poly
					(pts
						(arc
							(start 0.2032 -0.2286)
							(mid 0.275042 -0.198842)
							(end 0.3048 -0.127)
						)
						(arc
							(start 0.3048 0.127)
							(mid 0.275042 0.198842)
							(end 0.2032 0.2286)
						)
						(arc
							(start -0.2032 0.2286)
							(mid -0.275042 0.198842)
							(end -0.3048 0.127)
						)
						(arc
							(start -0.3048 -0.127)
							(mid -0.275042 -0.198842)
							(end -0.2032 -0.2286)
						)
					)
					(width 0)
					(fill yes)
				)
			)
		)
	)
	(footprint ""
		(layer "F.Cu")
		(at 55.0164 -30.226 90)
		(property "Reference" "R54"
			(at 0 0 90)
			(layer "F.SilkS")
			(hide yes)
			(effects
				(font
					(size 1.27 1.27)
				)
			)
		)
		(property "Value" "4K7R2F-GP"
			(at 0.064008 -4.679696 90)
			(unlocked yes)
			(layer "F.Fab")
			(hide yes)
			(effects
				(font
					(size 2.54 2.54)
					(thickness 0.381)
				)
			)
		)
		(property "Device Type" "R402H16"
			(at 0.064008 -6.203696 90)
			(unlocked yes)
			(layer "F.Fab")
			(hide yes)
			(effects
				(font
					(size 2.54 2.54)
					(thickness 0.381)
				)
			)
		)
		(duplicate_pad_numbers_are_jumpers no)
		(fp_line
			(start 0.508 -0.9398)
			(end -0.508 -0.9398)
			(stroke
				(width 0.1524)
				(type default)
			)
			(layer "F.SilkS")
		)
		(fp_line
			(start -0.508 -0.9398)
			(end -0.508 0.9398)
			(stroke
				(width 0.1524)
				(type default)
			)
			(layer "F.SilkS")
		)
		(fp_rect
			(start -0.508 0.9398)
			(end 0.508 -0.9398)
			(stroke
				(width 0)
				(type default)
			)
			(fill no)
			(layer "F.CrtYd")
		)
		(fp_rect
			(start -0.508 0.9398)
			(end 0.508 -0.9398)
			(stroke
				(width 0)
				(type default)
			)
			(fill no)
			(layer "F.Fab")
		)
		(pad "1" smd custom
			(at 0 -0.4445 90)
			(size 0.1397 0.1397)
			(layers "F.Cu" "F.Mask" "F.Paste")
			(net "RST_B_TS")
			(options
				(clearance outline)
				(anchor circle)
			)
			(primitives
				(gr_poly
					(pts
						(arc
							(start -0.1778 -0.2794)
							(mid -0.249642 -0.249642)
							(end -0.2794 -0.1778)
						)
						(arc
							(start -0.2794 0.1778)
							(mid -0.249642 0.249642)
							(end -0.1778 0.2794)
						)
						(arc
							(start 0.1778 0.2794)
							(mid 0.249642 0.249642)
							(end 0.2794 0.1778)
						)
						(arc
							(start 0.2794 -0.1778)
							(mid 0.249642 -0.249642)
							(end 0.1778 -0.2794)
						)
					)
					(width 0)
					(fill yes)
				)
			)
		)
		(pad "2" smd custom
			(at 0 0.4445 90)
			(size 0.1397 0.1397)
			(layers "F.Cu" "F.Mask" "F.Paste")
			(net "GND")
			(options
				(clearance outline)
				(anchor circle)
			)
			(primitives
				(gr_poly
					(pts
						(arc
							(start -0.1778 -0.2794)
							(mid -0.249642 -0.249642)
							(end -0.2794 -0.1778)
						)
						(arc
							(start -0.2794 0.1778)
							(mid -0.249642 0.249642)
							(end -0.1778 0.2794)
						)
						(arc
							(start 0.1778 0.2794)
							(mid 0.249642 0.249642)
							(end 0.2794 0.1778)
						)
						(arc
							(start 0.2794 -0.1778)
							(mid 0.249642 -0.249642)
							(end 0.1778 -0.2794)
						)
					)
					(width 0)
					(fill yes)
				)
			)
		)
	)
	(footprint ""
		(layer "F.Cu")
		(at 54.741064 -34.05759 180)
		(property "Reference" "R23"
			(at 0 0 180)
			(layer "F.SilkS")
			(hide yes)
			(effects
				(font
					(size 1.27 1.27)
				)
			)
		)
		(property "Value" "22KR2F-GP"
			(at 0.064008 -4.679696 180)
			(unlocked yes)
			(layer "F.Fab")
			(hide yes)
			(effects
				(font
					(size 2.54 2.54)
					(thickness 0.381)
				)
			)
		)
		(property "Device Type" "R402H16"
			(at 0.064008 -6.203696 180)
			(unlocked yes)
			(layer "F.Fab")
			(hide yes)
			(effects
				(font
					(size 2.54 2.54)
					(thickness 0.381)
				)
			)
		)
		(duplicate_pad_numbers_are_jumpers no)
		(fp_line
			(start 0.508 -0.9398)
			(end -0.508 -0.9398)
			(stroke
				(width 0.1524)
				(type default)
			)
			(layer "F.SilkS")
		)
		(fp_line
			(start -0.508 -0.9398)
			(end -0.508 0.9398)
			(stroke
				(width 0.1524)
				(type default)
			)
			(layer "F.SilkS")
		)
		(fp_rect
			(start -0.508 0.9398)
			(end 0.508 -0.9398)
			(stroke
				(width 0)
				(type default)
			)
			(fill no)
			(layer "F.CrtYd")
		)
		(fp_rect
			(start -0.508 0.9398)
			(end 0.508 -0.9398)
			(stroke
				(width 0)
				(type default)
			)
			(fill no)
			(layer "F.Fab")
		)
		(pad "1" smd custom
			(at 0 -0.4445 180)
			(size 0.1397 0.1397)
			(layers "F.Cu" "F.Mask" "F.Paste")
			(net "P3V3_STBY_B")
			(options
				(clearance outline)
				(anchor circle)
			)
			(primitives
				(gr_poly
					(pts
						(arc
							(start -0.1778 -0.2794)
							(mid -0.249642 -0.249642)
							(end -0.2794 -0.1778)
						)
						(arc
							(start -0.2794 0.1778)
							(mid -0.249642 0.249642)
							(end -0.1778 0.2794)
						)
						(arc
							(start 0.1778 0.2794)
							(mid 0.249642 0.249642)
							(end 0.2794 0.1778)
						)
						(arc
							(start 0.2794 -0.1778)
							(mid 0.249642 -0.249642)
							(end 0.1778 -0.2794)
						)
					)
					(width 0)
					(fill yes)
				)
			)
		)
		(pad "2" smd custom
			(at 0 0.4445 180)
			(size 0.1397 0.1397)
			(layers "F.Cu" "F.Mask" "F.Paste")
			(net "SYS_RESET_BTN_B")
			(options
				(clearance outline)
				(anchor circle)
			)
			(primitives
				(gr_poly
					(pts
						(arc
							(start -0.1778 -0.2794)
							(mid -0.249642 -0.249642)
							(end -0.2794 -0.1778)
						)
						(arc
							(start -0.2794 0.1778)
							(mid -0.249642 0.249642)
							(end -0.1778 0.2794)
						)
						(arc
							(start 0.1778 0.2794)
							(mid 0.249642 0.249642)
							(end 0.2794 0.1778)
						)
						(arc
							(start 0.2794 -0.1778)
							(mid 0.249642 -0.249642)
							(end 0.1778 -0.2794)
						)
					)
					(width 0)
					(fill yes)
				)
			)
		)
	)
	(footprint ""
		(layer "F.Cu")
		(at 33.6804 -12.3952 180)
		(property "Reference" "C32"
			(at 0 0 180)
			(layer "F.SilkS")
			(hide yes)
			(effects
				(font
					(size 1.27 1.27)
				)
			)
		)
		(property "Value" "SCD1U16V2KX-3GP"
			(at 1.1811 -2.7051 180)
			(unlocked yes)
			(layer "F.Fab")
			(hide yes)
			(effects
				(font
					(size 1.016 1.016)
					(thickness 0.1524)
				)
			)
		)
		(property "Device Type" "C402H22"
			(at 1.1811 -4.2291 180)
			(unlocked yes)
			(layer "F.Fab")
			(hide yes)
			(effects
				(font
					(size 1.016 1.016)
					(thickness 0.1524)
				)
			)
		)
		(duplicate_pad_numbers_are_jumpers no)
		(fp_rect
			(start -0.4318 0.9525)
			(end 0.4318 -0.9525)
			(stroke
				(width 0)
				(type default)
			)
			(fill no)
			(layer "F.CrtYd")
		)
		(fp_rect
			(start -0.4318 0.9525)
			(end 0.4318 -0.9525)
			(stroke
				(width 0)
				(type default)
			)
			(fill no)
			(layer "F.Fab")
		)
		(pad "1" smd custom
			(at 0 -0.4445 180)
			(size 0.1524 0.1524)
			(layers "F.Cu" "F.Mask" "F.Paste")
			(net "DEBUG_HDR_B_UART_SEL")
			(options
				(clearance outline)
				(anchor circle)
			)
			(primitives
				(gr_poly
					(pts
						(arc
							(start 0.3048 -0.2032)
							(mid 0.275042 -0.275042)
							(end 0.2032 -0.3048)
						)
						(arc
							(start -0.2032 -0.3048)
							(mid -0.275042 -0.275042)
							(end -0.3048 -0.2032)
						)
						(arc
							(start -0.3048 0.2032)
							(mid -0.275042 0.275042)
							(end -0.2032 0.3048)
						)
						(arc
							(start 0.2032 0.3048)
							(mid 0.275042 0.275042)
							(end 0.3048 0.2032)
						)
					)
					(width 0)
					(fill yes)
				)
			)
		)
		(pad "2" smd custom
			(at 0 0.4445 180)
			(size 0.1524 0.1524)
			(layers "F.Cu" "F.Mask" "F.Paste")
			(net "GND")
			(options
				(clearance outline)
				(anchor circle)
			)
			(primitives
				(gr_poly
					(pts
						(arc
							(start 0.3048 -0.2032)
							(mid 0.275042 -0.275042)
							(end 0.2032 -0.3048)
						)
						(arc
							(start -0.2032 -0.3048)
							(mid -0.275042 -0.275042)
							(end -0.3048 -0.2032)
						)
						(arc
							(start -0.3048 0.2032)
							(mid -0.275042 0.275042)
							(end -0.2032 0.3048)
						)
						(arc
							(start 0.2032 0.3048)
							(mid 0.275042 0.275042)
							(end 0.3048 0.2032)
						)
					)
					(width 0)
					(fill yes)
				)
			)
		)
	)
	(footprint ""
		(layer "F.Cu")
		(at 16.51 -7.366 180)
		(property "Reference" "U11"
			(at 0 0 180)
			(layer "F.SilkS")
			(hide yes)
			(effects
				(font
					(size 1.27 1.27)
				)
			)
		)
		(property "Value" "SNLVC1G126DCKR-GP"
			(at -2.3368 -8.6868 180)
			(unlocked yes)
			(layer "F.Fab")
			(hide yes)
			(effects
				(font
					(size 1.016 1.016)
					(thickness 0.1524)
				)
			)
		)
		(property "Device Type" "SC70-5H44"
			(at -2.3114 -10.414 180)
			(unlocked yes)
			(layer "F.Fab")
			(hide yes)
			(effects
				(font
					(size 1.016 1.016)
					(thickness 0.1524)
				)
			)
		)
		(duplicate_pad_numbers_are_jumpers no)
		(fp_line
			(start 1.3843 -1.8034)
			(end 1.3843 -1.1176)
			(stroke
				(width 0.3302)
				(type default)
			)
			(layer "F.SilkS")
		)
		(fp_line
			(start 1.27 1.7018)
			(end -1.27 1.7018)
			(stroke
				(width 0.1524)
				(type default)
			)
			(layer "F.SilkS")
		)
		(fp_line
			(start 1.27 -1.7018)
			(end 1.27 1.7018)
			(stroke
				(width 0.1524)
				(type default)
			)
			(layer "F.SilkS")
		)
		(fp_line
			(start 0.6604 -1.8034)
			(end 1.3843 -1.8034)
			(stroke
				(width 0.3302)
				(type default)
			)
			(layer "F.SilkS")
		)
		(fp_line
			(start -1.27 1.7018)
			(end -1.27 -1.7018)
			(stroke
				(width 0.1524)
				(type default)
			)
			(layer "F.SilkS")
		)
		(fp_line
			(start -1.27 -1.7018)
			(end 1.27 -1.7018)
			(stroke
				(width 0.1524)
				(type default)
			)
			(layer "F.SilkS")
		)
		(fp_rect
			(start -1.524 1.9558)
			(end 1.524 -1.9558)
			(stroke
				(width 0)
				(type default)
			)
			(fill no)
			(layer "F.CrtYd")
		)
		(fp_poly
			(pts
				(xy -1.524 -1.9558) (xy 1.524 -1.9558) (xy 1.524 1.9558) (xy -1.524 1.9558)
			)
			(stroke
				(width 0)
				(type default)
			)
			(fill no)
			(layer "F.Fab")
		)
		(pad "1" smd rect
			(at 0.65024 -0.8255 180)
			(size 0.4064 1.2192)
			(layers "F.Cu" "F.Mask" "F.Paste")
			(net "DEBUG_CARD_A_PRSNT")
		)
		(pad "2" smd rect
			(at 0 -0.8255 180)
			(size 0.4064 1.2192)
			(layers "F.Cu" "F.Mask" "F.Paste")
			(net "UART_DEBUG_A_RX")
		)
		(pad "3" smd rect
			(at -0.65024 -0.8255 180)
			(size 0.4064 1.2192)
			(layers "F.Cu" "F.Mask" "F.Paste")
			(net "GND")
		)
		(pad "4" smd rect
			(at -0.65024 0.8255 180)
			(size 0.4064 1.2192)
			(layers "F.Cu" "F.Mask" "F.Paste")
			(net "UART_A_RX")
		)
		(pad "5" smd rect
			(at 0.65024 0.8255 180)
			(size 0.4064 1.2192)
			(layers "F.Cu" "F.Mask" "F.Paste")
			(net "P3V3_STBY_A")
		)
	)
	(footprint ""
		(layer "F.Cu")
		(at 3.700526 -43.263058)
		(property "Reference" "D1"
			(at 0 0 0)
			(layer "F.SilkS")
			(hide yes)
			(effects
				(font
					(size 1.27 1.27)
				)
			)
		)
		(property "Value" "PESD3V3L4UW-GP"
			(at 2.2606 1.27 0)
			(unlocked yes)
			(layer "F.Fab")
			(hide yes)
			(effects
				(font
					(size 1.016 1.016)
					(thickness 0.1524)
				)
			)
		)
		(property "Device Type" "SOT-23-5-3H24"
			(at 2.2606 -0.254 0)
			(unlocked yes)
			(layer "F.Fab")
			(hide yes)
			(effects
				(font
					(size 1.016 1.016)
					(thickness 0.1524)
				)
			)
		)
		(duplicate_pad_numbers_are_jumpers no)
		(fp_line
			(start -1.143 0.254)
			(end -1.143 1.524)
			(stroke
				(width 0.3302)
				(type default)
			)
			(layer "F.SilkS")
		)
		(fp_line
			(start -1.143 1.524)
			(end 0.127 1.524)
			(stroke
				(width 0.3302)
				(type default)
			)
			(layer "F.SilkS")
		)
		(fp_line
			(start -1.0541 -1.4351)
			(end -1.0541 1.4351)
			(stroke
				(width 0.1524)
				(type default)
			)
			(layer "F.SilkS")
		)
		(fp_line
			(start -1.0541 1.4351)
			(end 1.0541 1.4351)
			(stroke
				(width 0.1524)
				(type default)
			)
			(layer "F.SilkS")
		)
		(fp_line
			(start 1.0541 -1.4351)
			(end -1.0541 -1.4351)
			(stroke
				(width 0.1524)
				(type default)
			)
			(layer "F.SilkS")
		)
		(fp_line
			(start 1.0541 1.4351)
			(end 1.0541 -1.4351)
			(stroke
				(width 0.1524)
				(type default)
			)
			(layer "F.SilkS")
		)
		(fp_poly
			(pts
				(xy -0.508 1.5113) (xy -0.0762 1.9431) (xy -0.9398 1.9431)
			)
			(stroke
				(width 0)
				(type default)
			)
			(fill yes)
			(layer "F.SilkS")
		)
		(fp_rect
			(start -1.3081 1.6891)
			(end 1.3081 -1.6891)
			(stroke
				(width 0)
				(type default)
			)
			(fill no)
			(layer "F.CrtYd")
		)
		(fp_rect
			(start -1.3081 1.6891)
			(end 1.3081 -1.6891)
			(stroke
				(width 0)
				(type default)
			)
			(fill no)
			(layer "F.Fab")
		)
		(pad "1" smd rect
			(at -0.500126 0.7239)
			(size 0.3048 0.9144)
			(layers "F.Cu" "F.Mask" "F.Paste")
			(net "UART_DEBUG_A_RX")
		)
		(pad "2" smd rect
			(at 0 0.7239)
			(size 0.3048 0.9144)
			(layers "F.Cu" "F.Mask" "F.Paste")
			(net "GND")
		)
		(pad "3" smd rect
			(at 0.500126 0.7239)
			(size 0.3048 0.9144)
			(layers "F.Cu" "F.Mask" "F.Paste")
			(net "I2C_DEBUG_A_SDA")
		)
		(pad "4" smd rect
			(at 0.500126 -0.7239)
			(size 0.3048 0.9144)
			(layers "F.Cu" "F.Mask" "F.Paste")
			(net "I2C_DEBUG_A_SCL")
		)
		(pad "5" smd rect
			(at -0.500126 -0.7239)
			(size 0.3048 0.9144)
			(layers "F.Cu" "F.Mask" "F.Paste")
			(net "UART_DEBUG_A_TX")
		)
	)
	(footprint ""
		(layer "F.Cu")
		(at 3.3528 -47.7266 90)
		(property "Reference" "TP7"
			(at 0 0 90)
			(layer "F.SilkS")
			(hide yes)
			(effects
				(font
					(size 1.27 1.27)
				)
			)
		)
		(property "Value" "TPAD32-GP"
			(at -0.0508 -1.6764 90)
			(unlocked yes)
			(layer "F.Fab")
			(hide yes)
			(effects
				(font
					(size 1.016 1.016)
					(thickness 0.1524)
				)
			)
		)
		(property "Device Type" "TPAD32"
			(at -0.0508 -3.2004 90)
			(unlocked yes)
			(layer "F.Fab")
			(hide yes)
			(effects
				(font
					(size 1.016 1.016)
					(thickness 0.1524)
				)
			)
		)
		(duplicate_pad_numbers_are_jumpers no)
		(fp_poly
			(pts
				(arc
					(start 0 0.4064)
					(mid 0 -0.4064)
					(end 0 0.4064)
				)
			)
			(stroke
				(width 0)
				(type default)
			)
			(fill no)
			(layer "F.CrtYd")
		)
		(fp_poly
			(pts
				(arc
					(start 0 0.7112)
					(mid 0 -0.7112)
					(end 0 0.7112)
				)
			)
			(stroke
				(width 0)
				(type default)
			)
			(fill no)
			(layer "F.Fab")
		)
		(pad "1" smd circle
			(at 0 0 90)
			(size 0.8128 0.8128)
			(layers "F.Cu" "F.Mask" "F.Paste")
			(net "TEMP_1_ALERT")
		)
	)
)
